FILE_TYPE = MACRO_DRAWING;
SET COLOR_WIRE YELLOW;
SET COLOR_PROP MONO;
SET COLOR_DOT WHITE;
SET COLOR_ARC YELLOW;
SET COLOR_BODY GREEN;
SET COLOR_NOTE MONO;
SET PROP_DISPLAY VALUE;
SET PAGE_NUMBER P266;
FORCEADD INTEL_CORP_BPAGE..1
(-1300 1725);
FORCEPROP 1 LAST CDS_CON_LAST_MODIFIED Fri Jun 16 17:49:41 2017
J 0
(-2725 2050);
PAINT ORANGE (-2725 2050);
DISPLAY INVISIBLE (-2725 2050);
FORCEPROP 1 LAST CUSTOM_TXT_CDS <CURRENT_DESIGN_SHEET> OF <TOTAL_DESIGN_SHEETS>
J 0
(-1800 1750);
PAINT ORANGE (-1800 1750);
FORCEPROP 2 LAST CUSTOM_TXT_CDS <XR_PAGE_TITLE>
J 0
(-9190 6975);
DISPLAY 0.638298 (-9190 6975);
PAINT PINK (-9190 6975);
DISPLAY INVISIBLE (-9190 6975);
FORCEPROP 2 LAST CUSTOM_TXT_CDS <CON_LAST_MODIFIED>
J 0
(-5300 1825);
PAINT ORANGE (-5300 1825);
FORCEPROP 1 LAST SCH_TITLE JTAG DEBUG HEADER BLOCK DIAGRAM
J 0
(-9250 1775);
DISPLAY 2.468085 (-9250 1775);
PAINT ORANGE (-9250 1775);
FORCEPROP 2 LAST PAGE_BORDER TRUE
J 0
(-9190 6975);
DISPLAY 0.638298 (-9190 6975);
PAINT PINK (-9190 6975);
DISPLAY INVISIBLE (-9190 6975);
FORCEPROP 2 LAST CDS_LIB mstr_symbols
J 0
(-1300 1725);
PAINT MONO (-1300 1725);
DISPLAY INVISIBLE (-1300 1725);
FORCEPROP 1 LAST COMMENT_BODY TRUE
J 0
(-1288 1737);
DISPLAY 0.468085 (-1288 1737);
PAINT GREEN (-1288 1737);
DISPLAY INVISIBLE (-1288 1737);
FORCEPROP 2 LAST CDS_XR_PAGE_TITLE CR-270 : @BASEBOARD_FAB2_LIB.BASEBOARD_FAB2(SCH_1):PAGE270
J 0
(-9190 6975);
DISPLAY 0.638298 (-9190 6975);
PAINT PINK (-9190 6975);
DISPLAY INVISIBLE (-9190 6975);
FORCENOTE
$CDS_IMAGE|JTAG Debug Header Block diagram_20161011.jpg|6860|4750
(-5275 4325) 0;
DISPLAY LEFT (-5275 4325);
QUIT
